# ZAIUS-LV_CARD-EVT1-X00-BOM-X01_20160825.xls — Single-Sole Source Parts List (bom)
| FOXCONN TECHNOLOGY GROUP |  |  |  |  |  |  |  |  |  |  |  |  |  |  |  |  |  |
| BILL OF MATERIAL |  |  |  |  |  |  |  |  |  |  |  |  |  |  |  |  |  |
| REV OF  BOM |  | CUSTOMER | DELL |  | CUSTOMER P/N |  | PWA P/N： | PWA DESCRIPTION |  |  | PRODUCT CODE |  |  | PWA REV |  | DATE |  |
| Sourcing (Single or Sole | Critical Commodity (Y or N) | Component Class (1, 2, Other) | Dell PSL (Y/N) | Item Number | Foxconn P/N | Dell P/N | Part Description | Mfr. 1 | Mfr Part # 1 | Proposed Mfr. 2 | Proposed Mfr. 2 PN | Qty | RoHS Status | Location | 2nd Source Qual Build: | Dell Comments | ODM Comments |
